(kicad_pcb
	(version 20260206)
	(generator "pcbnew")
	(generator_version "10.0")
	(general
		(thickness 1.6)
		(legacy_teardrops no)
	)
	(paper "A4")
	(title_block
		(title "Wiwynn_Tioga_Pass_MB.brd")
		(comment 1 "Tioga Pass / footprints 1758-1761 of 4770")
	)
	(layers
		(0 "F.Cu" signal "TOP")
		(4 "In1.Cu" signal "L2GND")
		(6 "In2.Cu" signal "L3")
		(8 "In3.Cu" signal "L4GND")
		(10 "In4.Cu" signal "L5")
		(12 "In5.Cu" signal "L6GND")
		(14 "In6.Cu" signal "L7VCC")
		(16 "In7.Cu" signal "L8VCC")
		(18 "In8.Cu" signal "L9GND")
		(20 "In9.Cu" signal "L10")
		(22 "In10.Cu" signal "L11GND")
		(24 "In11.Cu" signal "L12")
		(26 "In12.Cu" signal "L13GND")
		(2 "B.Cu" signal "BOTTOM")
		(9 "F.Adhes" user "F.Adhesive")
		(11 "B.Adhes" user "B.Adhesive")
		(13 "F.Paste" user "Package Geometry/Pastemask Top")
		(15 "B.Paste" user "Package Geometry/Pastemask Bottom")
		(5 "F.SilkS" user "Ref Des/Silkscreen Top")
		(7 "B.SilkS" user "Ref Des/Silkscreen Bottom")
		(1 "F.Mask" user "Board Geometry/Soldermask Top")
		(3 "B.Mask" user "Board Geometry/Soldermask Bottom")
		(17 "Dwgs.User" user "User.Drawings")
		(19 "Cmts.User" user "User.Comments")
		(21 "Eco1.User" user "User.Eco1")
		(23 "Eco2.User" user "User.Eco2")
		(25 "Edge.Cuts" user "Board Geometry/Outline")
		(27 "Margin" user)
		(31 "F.CrtYd" user "Package Geometry/Place Bound Top")
		(29 "B.CrtYd" user "Package Geometry/Place Bound Bottom")
		(35 "F.Fab" user "Ref Des/Assembly Top")
		(33 "B.Fab" user "Ref Des/Assembly Bottom")
	)
	(footprint ""
		(layer "F.Cu")
		(at -1.999996 -82.63001 -90)
		(property "Reference" "J1D1"
			(at 0 0 270)
			(layer "F.SilkS")
			(hide yes)
			(effects
				(font
					(size 1.27 1.27)
				)
			)
		)
		(property "Value" "*"
			(at -18.3388 15.2273 270)
			(unlocked yes)
			(layer "F.Fab")
			(hide yes)
			(effects
				(font
					(size 1.27 1.016)
					(thickness 0.1524)
				)
			)
		)
		(property "Device Type" "FCI-CONN12-2R-GP_CONN-G5-FCI-CA"
			(at -18.3388 13.7033 270)
			(unlocked yes)
			(layer "F.Fab")
			(hide yes)
			(effects
				(font
					(size 1.27 1.016)
					(thickness 0.1524)
				)
			)
		)
		(duplicate_pad_numbers_are_jumpers no)
		(fp_line
			(start -6.1849 3.999992)
			(end 6.1849 3.999992)
			(stroke
				(width 0.1524)
				(type default)
			)
			(layer "F.SilkS")
		)
		(fp_line
			(start 6.1849 3.999992)
			(end 6.1849 -14.8971)
			(stroke
				(width 0.1524)
				(type default)
			)
			(layer "F.SilkS")
		)
		(fp_line
			(start -6.1849 -14.8971)
			(end -6.1849 3.999992)
			(stroke
				(width 0.1524)
				(type default)
			)
			(layer "F.SilkS")
		)
		(fp_line
			(start 6.1849 -14.8971)
			(end -6.1849 -14.8971)
			(stroke
				(width 0.1524)
				(type default)
			)
			(layer "F.SilkS")
		)
		(fp_poly
			(pts
				(xy -6.1849 3.999992) (xy 6.1849 3.999992) (xy 6.1849 -14.8971) (xy -6.1849 -14.8971)
			)
			(stroke
				(width 0)
				(type default)
			)
			(fill yes)
			(layer "F.SilkS")
		)
		(fp_poly
			(pts
				(arc
					(start -4.064 1.331976)
					(mid -4.318 1.585976)
					(end -4.572 1.331976)
				)
				(arc
					(start -4.572 0.569976)
					(mid -4.318 0.315976)
					(end -4.064 0.569976)
				)
			)
			(stroke
				(width 0)
				(type default)
			)
			(fill yes)
			(layer "F.SilkS")
		)
		(fp_poly
			(pts
				(arc
					(start -4.064 -0.66802)
					(mid -4.318 -0.41402)
					(end -4.572 -0.66802)
				)
				(arc
					(start -4.572 -1.43002)
					(mid -4.318 -1.68402)
					(end -4.064 -1.43002)
				)
			)
			(stroke
				(width 0)
				(type default)
			)
			(fill yes)
			(layer "F.SilkS")
		)
		(fp_poly
			(pts
				(arc
					(start -4.064 -2.668016)
					(mid -4.318 -2.414016)
					(end -4.572 -2.668016)
				)
				(arc
					(start -4.572 -3.430016)
					(mid -4.318 -3.684016)
					(end -4.064 -3.430016)
				)
			)
			(stroke
				(width 0)
				(type default)
			)
			(fill yes)
			(layer "F.SilkS")
		)
		(fp_poly
			(pts
				(arc
					(start -4.064 -6.668008)
					(mid -4.318 -6.414008)
					(end -4.572 -6.668008)
				)
				(arc
					(start -4.572 -7.430008)
					(mid -4.318 -7.684008)
					(end -4.064 -7.430008)
				)
			)
			(stroke
				(width 0)
				(type default)
			)
			(fill yes)
			(layer "F.SilkS")
		)
		(fp_poly
			(pts
				(arc
					(start -4.064 -8.668004)
					(mid -4.318 -8.414004)
					(end -4.572 -8.668004)
				)
				(arc
					(start -4.572 -9.430004)
					(mid -4.318 -9.684004)
					(end -4.064 -9.430004)
				)
			)
			(stroke
				(width 0)
				(type default)
			)
			(fill yes)
			(layer "F.SilkS")
		)
		(fp_poly
			(pts
				(arc
					(start -4.064 -10.668)
					(mid -4.318 -10.414)
					(end -4.572 -10.668)
				)
				(arc
					(start -4.572 -11.43)
					(mid -4.318 -11.684)
					(end -4.064 -11.43)
				)
			)
			(stroke
				(width 0)
				(type default)
			)
			(fill yes)
			(layer "F.SilkS")
		)
		(fp_rect
			(start -8.5598 6.5532)
			(end 8.5598 -16.5608)
			(stroke
				(width 0)
				(type default)
			)
			(fill no)
			(layer "B.CrtYd")
		)
		(fp_rect
			(start -5.9309 16.3449)
			(end 5.9309 -14.6431)
			(stroke
				(width 0)
				(type default)
			)
			(fill no)
			(layer "F.CrtYd")
		)
		(fp_poly
			(pts
				(xy -10.9347 21.3487) (xy -10.9347 -19.6469) (xy 10.9347 -19.6469) (xy 10.9347 -0.00635) (xy 6.4389 -0.00635)
				(xy 6.4389 -15.1511) (xy -6.4389 -15.1511) (xy -6.4389 16.8529) (xy 6.4389 16.8529) (xy 6.4389 0.00635)
				(xy 10.9347 0.00635) (xy 10.9347 21.3487)
			)
			(stroke
				(width 0)
				(type default)
			)
			(fill no)
			(layer "F.CrtYd")
		)
		(fp_poly
			(pts
				(xy -6.4389 16.8529) (xy -6.4389 -15.1511) (xy 6.4389 -15.1511) (xy 6.4389 -0.00635) (xy 5.9309 -0.00635)
				(xy 5.9309 -14.6431) (xy -5.9309 -14.6431) (xy -5.9309 16.3449) (xy 5.9309 16.3449) (xy 5.9309 0.00635)
				(xy 6.4389 0.00635) (xy 6.4389 16.8529)
			)
			(stroke
				(width 0)
				(type default)
			)
			(fill no)
			(layer "F.CrtYd")
		)
		(fp_rect
			(start -13.5636 11.557)
			(end 13.5636 -21.5646)
			(stroke
				(width 0)
				(type default)
			)
			(fill no)
			(layer "B.Fab")
		)
		(fp_rect
			(start -8.5598 6.5532)
			(end 8.5598 -16.5608)
			(stroke
				(width 0)
				(type default)
			)
			(fill no)
			(layer "B.Fab")
		)
		(fp_rect
			(start -15.9385 26.3525)
			(end 15.9385 -24.6507)
			(stroke
				(width 0)
				(type default)
			)
			(fill no)
			(layer "F.Fab")
		)
		(fp_rect
			(start -10.9347 21.3487)
			(end 10.9347 -19.6469)
			(stroke
				(width 0)
				(type default)
			)
			(fill no)
			(layer "F.Fab")
		)
		(fp_rect
			(start -6.4389 16.8529)
			(end 6.4389 -15.1511)
			(stroke
				(width 0)
				(type default)
			)
			(fill no)
			(layer "F.Fab")
		)
		(fp_text user "Slit"
			(at -2.31521 6.78307 270)
			(unlocked yes)
			(layer "F.SilkS")
			(effects
				(font
					(size 1.27 1.016)
					(thickness 0.1524)
				)
				(justify left)
			)
		)
		(fp_text user "Press Fit"
			(at -5.1054 -12.6111 270)
			(unlocked yes)
			(layer "F.SilkS")
			(effects
				(font
					(size 1.27 1.016)
					(thickness 0.1524)
				)
				(justify left)
			)
		)
		(fp_text user "Can not place BGA,CSP,Wave Solder Component"
			(at -25.73655 8.95604 270)
			(unlocked yes)
			(layer "B.Fab")
			(effects
				(font
					(size 1.27 1.016)
					(thickness 0.1524)
				)
				(justify left)
			)
		)
		(fp_text user "Can not place BGA,CSP,Wave Solder Component"
			(at -25.82926 18.53946 270)
			(unlocked yes)
			(layer "F.Fab")
			(effects
				(font
					(size 1.27 1.016)
					(thickness 0.1524)
				)
				(justify left)
			)
		)
		(fp_text user "High Limit 2mm"
			(at -8.4963 13.35786 270)
			(unlocked yes)
			(layer "F.Fab")
			(effects
				(font
					(size 1.27 1.016)
					(thickness 0.1524)
				)
				(justify left)
			)
		)
		(pad "" np_thru_hole circle
			(at 0 0 270)
			(size 0.254 0.254)
			(drill 2.1336)
			(layers "*.Cu" "*.Mask")
			(clearance 1.2954)
			(thermal_gap 1.2954)
		)
		(pad "1_1" thru_hole circle
			(at 2.999994 -6.999986 270)
			(size 1.1176 1.1176)
			(drill 0.749808)
			(layers "*.Cu" "*.Mask")
			(remove_unused_layers no)
			(net "P12V_PSU")
			(clearance 0.1778)
			(thermal_gap 0.1778)
		)
		(pad "1_2" thru_hole circle
			(at 2.999994 -8.999982 270)
			(size 1.1176 1.1176)
			(drill 0.749808)
			(layers "*.Cu" "*.Mask")
			(remove_unused_layers no)
			(net "P12V_PSU")
			(clearance 0.1778)
			(thermal_gap 0.1778)
		)
		(pad "1_3" thru_hole circle
			(at 2.999994 -10.999978 270)
			(size 1.1176 1.1176)
			(drill 0.749808)
			(layers "*.Cu" "*.Mask")
			(remove_unused_layers no)
			(net "P12V_PSU")
			(clearance 0.1778)
			(thermal_gap 0.1778)
		)
		(pad "2_1" thru_hole circle
			(at -2.999994 -6.999986 270)
			(size 1.1176 1.1176)
			(drill 0.749808)
			(layers "*.Cu" "*.Mask")
			(remove_unused_layers no)
			(net "P12V_PSU")
			(clearance 0.1778)
			(thermal_gap 0.1778)
		)
		(pad "2_2" thru_hole circle
			(at -2.999994 -8.999982 270)
			(size 1.1176 1.1176)
			(drill 0.749808)
			(layers "*.Cu" "*.Mask")
			(remove_unused_layers no)
			(net "P12V_PSU")
			(clearance 0.1778)
			(thermal_gap 0.1778)
		)
		(pad "2_3" thru_hole circle
			(at -2.999994 -10.999978 270)
			(size 1.1176 1.1176)
			(drill 0.749808)
			(layers "*.Cu" "*.Mask")
			(remove_unused_layers no)
			(net "P12V_PSU")
			(clearance 0.1778)
			(thermal_gap 0.1778)
		)
		(pad "3_1" thru_hole circle
			(at -2.999994 0.999998 270)
			(size 1.1176 1.1176)
			(drill 0.749808)
			(layers "*.Cu" "*.Mask")
			(remove_unused_layers no)
			(net "GND")
			(clearance 0.1778)
			(thermal_gap 0.1778)
		)
		(pad "3_2" thru_hole circle
			(at -2.999994 -0.999998 270)
			(size 1.1176 1.1176)
			(drill 0.749808)
			(layers "*.Cu" "*.Mask")
			(remove_unused_layers no)
			(net "GND")
			(clearance 0.1778)
			(thermal_gap 0.1778)
		)
		(pad "3_3" thru_hole circle
			(at -2.999994 -2.999994 270)
			(size 1.1176 1.1176)
			(drill 0.749808)
			(layers "*.Cu" "*.Mask")
			(remove_unused_layers no)
			(net "GND")
			(clearance 0.1778)
			(thermal_gap 0.1778)
		)
		(pad "4_1" thru_hole circle
			(at 2.999994 0.999998 270)
			(size 1.1176 1.1176)
			(drill 0.749808)
			(layers "*.Cu" "*.Mask")
			(remove_unused_layers no)
			(net "GND")
			(clearance 0.1778)
			(thermal_gap 0.1778)
		)
		(pad "4_2" thru_hole circle
			(at 2.999994 -0.999998 270)
			(size 1.1176 1.1176)
			(drill 0.749808)
			(layers "*.Cu" "*.Mask")
			(remove_unused_layers no)
			(net "GND")
			(clearance 0.1778)
			(thermal_gap 0.1778)
		)
		(pad "4_3" thru_hole circle
			(at 2.999994 -2.999994 270)
			(size 1.1176 1.1176)
			(drill 0.749808)
			(layers "*.Cu" "*.Mask")
			(remove_unused_layers no)
			(net "GND")
			(clearance 0.1778)
			(thermal_gap 0.1778)
		)
		(zone
			(layers "F.Cu" "B.Cu" "In1.Cu" "In2.Cu" "In3.Cu" "In4.Cu" "In5.Cu" "In6.Cu"
				"In7.Cu" "In8.Cu" "In9.Cu" "In10.Cu" "In11.Cu" "In12.Cu"
			)
			(hatch none 0.5)
			(connect_pads
				(clearance 0)
			)
			(min_thickness 0.25)
			(keepout
				(tracks not_allowed)
				(vias allowed)
				(pads allowed)
				(copperpour not_allowed)
				(footprints allowed)
			)
			(placement
				(enabled no)
				(sheetname "")
			)
			(fill
				(thermal_gap 0.5)
				(thermal_bridge_width 0.5)
				(island_removal_mode 0)
			)
			(polygon
				(pts
					(arc
						(start -0.628396 -82.63001)
						(mid -3.371596 -82.63001)
						(end -0.628396 -82.63001)
					)
				)
			)
		)
	)
	(footprint ""
		(layer "F.Cu")
		(at 340.995 -106.426 90)
		(property "Reference" "R7C24"
			(at 0 0 90)
			(layer "F.SilkS")
			(hide yes)
			(effects
				(font
					(size 1.27 1.27)
				)
			)
		)
		(property "Value" ""
			(at 0 0 90)
			(layer "F.Fab")
			(effects
				(font
					(size 1.27 1.27)
				)
			)
		)
		(duplicate_pad_numbers_are_jumpers no)
		(fp_poly
			(pts
				(xy -0.2794 -0.1016) (xy 0.2794 -0.1016) (xy 0.2794 0.9906) (xy -0.2794 0.9906)
			)
			(stroke
				(width 0)
				(type default)
			)
			(fill no)
			(layer "F.CrtYd")
		)
		(fp_line
			(start 0.2794 -0.1016)
			(end -0.2794 -0.1016)
			(stroke
				(width 0.1)
				(type default)
			)
			(layer "F.Fab")
		)
		(fp_line
			(start -0.2794 -0.1016)
			(end -0.2794 0.9906)
			(stroke
				(width 0.1)
				(type default)
			)
			(layer "F.Fab")
		)
		(fp_line
			(start 0.2794 0.9906)
			(end 0.2794 -0.1016)
			(stroke
				(width 0.1)
				(type default)
			)
			(layer "F.Fab")
		)
		(fp_line
			(start -0.2794 0.9906)
			(end 0.2794 0.9906)
			(stroke
				(width 0.1)
				(type default)
			)
			(layer "F.Fab")
		)
		(pad "1" smd rect
			(at 0 0 90)
			(size 0.508 0.508)
			(layers "F.Cu" "F.Mask" "F.Paste")
			(net "VR_PVCCMCP_CPU0_XADDR2")
		)
		(pad "2" smd rect
			(at 0 0.889 90)
			(size 0.508 0.508)
			(layers "F.Cu" "F.Mask" "F.Paste")
			(net "GND")
		)
		(zone
			(layer "F.Cu")
			(hatch none 0.5)
			(connect_pads
				(clearance 0)
			)
			(min_thickness 0.25)
			(keepout
				(tracks allowed)
				(vias not_allowed)
				(pads allowed)
				(copperpour not_allowed)
				(footprints allowed)
			)
			(placement
				(enabled no)
				(sheetname "")
			)
			(fill
				(thermal_gap 0.5)
				(thermal_bridge_width 0.5)
				(island_removal_mode 0)
			)
			(polygon
				(pts
					(xy 341.249 -106.172) (xy 341.249 -106.68) (xy 341.63 -106.68) (xy 341.63 -106.172)
				)
			)
		)
		(zone
			(layer "F.Cu")
			(hatch none 0.5)
			(connect_pads
				(clearance 0)
			)
			(min_thickness 0.25)
			(keepout
				(tracks not_allowed)
				(vias allowed)
				(pads allowed)
				(copperpour not_allowed)
				(footprints allowed)
			)
			(placement
				(enabled no)
				(sheetname "")
			)
			(fill
				(thermal_gap 0.5)
				(thermal_bridge_width 0.5)
				(island_removal_mode 0)
			)
			(polygon
				(pts
					(xy 341.63 -106.172) (xy 341.63 -106.68) (xy 341.249 -106.68) (xy 341.249 -106.172)
				)
			)
		)
	)
	(footprint ""
		(layer "F.Cu")
		(at 348.2086 -10.2108 90)
		(property "Reference" "C7G33"
			(at 0 0 90)
			(layer "F.SilkS")
			(hide yes)
			(effects
				(font
					(size 1.27 1.27)
				)
			)
		)
		(property "Value" ""
			(at 0 0 90)
			(layer "F.Fab")
			(effects
				(font
					(size 1.27 1.27)
				)
			)
		)
		(duplicate_pad_numbers_are_jumpers no)
		(fp_poly
			(pts
				(xy 0.3048 -0.1016) (xy 0.3048 0.9906) (xy -0.3048 0.9906) (xy -0.3048 -0.1016)
			)
			(stroke
				(width 0)
				(type default)
			)
			(fill no)
			(layer "F.CrtYd")
		)
		(fp_line
			(start 0.3048 -0.1016)
			(end -0.3048 -0.1016)
			(stroke
				(width 0.1)
				(type default)
			)
			(layer "F.Fab")
		)
		(fp_line
			(start -0.3048 -0.1016)
			(end -0.3048 0.9906)
			(stroke
				(width 0.1)
				(type default)
			)
			(layer "F.Fab")
		)
		(fp_line
			(start 0.3048 0.9906)
			(end 0.3048 -0.1016)
			(stroke
				(width 0.1)
				(type default)
			)
			(layer "F.Fab")
		)
		(fp_line
			(start -0.3048 0.9906)
			(end 0.3048 0.9906)
			(stroke
				(width 0.1)
				(type default)
			)
			(layer "F.Fab")
		)
		(pad "1" smd rect
			(at 0 0 90)
			(size 0.508 0.508)
			(layers "F.Cu" "F.Mask" "F.Paste")
			(net "VR_PVDDQ_ABC_PH1_VCIN")
		)
		(pad "2" smd rect
			(at 0 0.889 90)
			(size 0.508 0.508)
			(layers "F.Cu" "F.Mask" "F.Paste")
			(net "GND")
		)
		(zone
			(layer "F.Cu")
			(hatch none 0.5)
			(connect_pads
				(clearance 0)
			)
			(min_thickness 0.25)
			(keepout
				(tracks allowed)
				(vias not_allowed)
				(pads allowed)
				(copperpour not_allowed)
				(footprints allowed)
			)
			(placement
				(enabled no)
				(sheetname "")
			)
			(fill
				(thermal_gap 0.5)
				(thermal_bridge_width 0.5)
				(island_removal_mode 0)
			)
			(polygon
				(pts
					(xy 348.4626 -9.9568) (xy 348.4626 -10.4648) (xy 348.8436 -10.4648) (xy 348.8436 -9.9568)
				)
			)
		)
		(zone
			(layer "F.Cu")
			(hatch none 0.5)
			(connect_pads
				(clearance 0)
			)
			(min_thickness 0.25)
			(keepout
				(tracks not_allowed)
				(vias allowed)
				(pads allowed)
				(copperpour not_allowed)
				(footprints allowed)
			)
			(placement
				(enabled no)
				(sheetname "")
			)
			(fill
				(thermal_gap 0.5)
				(thermal_bridge_width 0.5)
				(island_removal_mode 0)
			)
			(polygon
				(pts
					(xy 348.8436 -9.9568) (xy 348.8436 -10.4648) (xy 348.4626 -10.4648) (xy 348.4626 -9.9568)
				)
			)
		)
	)
	(footprint ""
		(layer "F.Cu")
		(at 342.2142 -94.107 90)
		(property "Reference" "CT72"
			(at -0.8382 -0.67818 90)
			(unlocked yes)
			(layer "F.SilkS")
			(effects
				(font
					(size 0.4064 0.254)
					(thickness 0.1524)
				)
				(justify left)
			)
		)
		(property "Value" ""
			(at 0 0 90)
			(layer "F.Fab")
			(effects
				(font
					(size 1.27 1.27)
				)
			)
		)
		(duplicate_pad_numbers_are_jumpers no)
		(fp_poly
			(pts
				(xy 0.3048 -0.1016) (xy 0.3048 0.9906) (xy -0.3048 0.9906) (xy -0.3048 -0.1016)
			)
			(stroke
				(width 0)
				(type default)
			)
			(fill no)
			(layer "F.CrtYd")
		)
		(fp_line
			(start 0.3048 -0.1016)
			(end -0.3048 -0.1016)
			(stroke
				(width 0.1)
				(type default)
			)
			(layer "F.Fab")
		)
		(fp_line
			(start -0.3048 -0.1016)
			(end -0.3048 0.9906)
			(stroke
				(width 0.1)
				(type default)
			)
			(layer "F.Fab")
		)
		(fp_line
			(start 0.3048 0.9906)
			(end 0.3048 -0.1016)
			(stroke
				(width 0.1)
				(type default)
			)
			(layer "F.Fab")
		)
		(fp_line
			(start -0.3048 0.9906)
			(end 0.3048 0.9906)
			(stroke
				(width 0.1)
				(type default)
			)
			(layer "F.Fab")
		)
		(pad "1" smd rect
			(at 0 0 90)
			(size 0.508 0.508)
			(layers "F.Cu" "F.Mask" "F.Paste")
			(net "VR_PVCCIO_CPU0_PH1_SW")
		)
		(pad "2" smd rect
			(at 0 0.889 90)
			(size 0.508 0.508)
			(layers "F.Cu" "F.Mask" "F.Paste")
			(net "VR_PVCCIO_CPU0_PH1_SW_RC")
		)
		(zone
			(layer "F.Cu")
			(hatch none 0.5)
			(connect_pads
				(clearance 0)
			)
			(min_thickness 0.25)
			(keepout
				(tracks allowed)
				(vias not_allowed)
				(pads allowed)
				(copperpour not_allowed)
				(footprints allowed)
			)
			(placement
				(enabled no)
				(sheetname "")
			)
			(fill
				(thermal_gap 0.5)
				(thermal_bridge_width 0.5)
				(island_removal_mode 0)
			)
			(polygon
				(pts
					(xy 342.4682 -93.853) (xy 342.4682 -94.361) (xy 342.8492 -94.361) (xy 342.8492 -93.853)
				)
			)
		)
		(zone
			(layer "F.Cu")
			(hatch none 0.5)
			(connect_pads
				(clearance 0)
			)
			(min_thickness 0.25)
			(keepout
				(tracks not_allowed)
				(vias allowed)
				(pads allowed)
				(copperpour not_allowed)
				(footprints allowed)
			)
			(placement
				(enabled no)
				(sheetname "")
			)
			(fill
				(thermal_gap 0.5)
				(thermal_bridge_width 0.5)
				(island_removal_mode 0)
			)
			(polygon
				(pts
					(xy 342.8492 -93.853) (xy 342.8492 -94.361) (xy 342.4682 -94.361) (xy 342.4682 -93.853)
				)
			)
		)
	)
)
